(kicad_pcb
	(version 20260206)
	(generator "pcbnew")
	(generator_version "10.0")
	(general
		(thickness 1.6)
		(legacy_teardrops no)
	)
	(paper "A4")
	(title_block
		(title "v1-tray-backplane — T6M_tray_BP_c_1023_1120.brd")
		(comment 1 "Open CloudServer (Microsoft) / footprints 38-42 of 170")
	)
	(layers
		(0 "F.Cu" signal "TOP")
		(4 "In1.Cu" signal "GND")
		(6 "In2.Cu" signal "IN1")
		(8 "In3.Cu" signal "VCC")
		(10 "In4.Cu" signal "VCC1")
		(12 "In5.Cu" signal "IN2")
		(14 "In6.Cu" signal "GND1")
		(2 "B.Cu" signal "BOTTOM")
		(9 "F.Adhes" user "F.Adhesive")
		(11 "B.Adhes" user "B.Adhesive")
		(13 "F.Paste" user "Package Geometry/Pastemask Top")
		(15 "B.Paste" user "Package Geometry/Pastemask Bottom")
		(5 "F.SilkS" user "Ref Des/Silkscreen Top")
		(7 "B.SilkS" user "Ref Des/Silkscreen Bottom")
		(1 "F.Mask" user "Board Geometry/Soldermask Top")
		(3 "B.Mask" user "Board Geometry/Soldermask Bottom")
		(17 "Dwgs.User" user "User.Drawings")
		(19 "Cmts.User" user "User.Comments")
		(21 "Eco1.User" user "User.Eco1")
		(23 "Eco2.User" user "User.Eco2")
		(25 "Edge.Cuts" user "Board Geometry/Outline")
		(27 "Margin" user)
		(31 "F.CrtYd" user "Package Geometry/Place Bound Top")
		(29 "B.CrtYd" user "Package Geometry/Place Bound Bottom")
		(35 "F.Fab" user "Ref Des/Assembly Top")
		(33 "B.Fab" user "Ref Des/Assembly Bottom")
	)
	(footprint ""
		(layer "F.Cu")
		(at 393.484862 -28.4099 180)
		(property "Reference" "U4"
			(at -7.110476 -9.509252 0)
			(unlocked yes)
			(layer "F.SilkS")
			(effects
				(font
					(size 0.7874 0.5842)
					(thickness 0.1524)
				)
				(justify left)
			)
		)
		(property "Value" ""
			(at 0 0 180)
			(layer "F.Fab")
			(effects
				(font
					(size 1.27 1.27)
				)
			)
		)
		(duplicate_pad_numbers_are_jumpers no)
		(fp_line
			(start 6.949948 8.32993)
			(end 6.949948 5.7912)
			(stroke
				(width 0.1524)
				(type default)
			)
			(layer "F.SilkS")
		)
		(fp_line
			(start 6.949948 4.572)
			(end 6.949948 0)
			(stroke
				(width 0.1524)
				(type default)
			)
			(layer "F.SilkS")
		)
		(fp_line
			(start 6.949948 0)
			(end 6.949948 -3.670046)
			(stroke
				(width 0.1524)
				(type default)
			)
			(layer "F.SilkS")
		)
		(fp_line
			(start 6.949948 -3.670046)
			(end 0 -3.670046)
			(stroke
				(width 0.1524)
				(type default)
			)
			(layer "F.SilkS")
		)
		(fp_line
			(start 0 -3.670046)
			(end -6.949948 -3.670046)
			(stroke
				(width 0.1524)
				(type default)
			)
			(layer "F.SilkS")
		)
		(fp_line
			(start -6.949948 8.32993)
			(end 6.949948 8.32993)
			(stroke
				(width 0.1524)
				(type default)
			)
			(layer "F.SilkS")
		)
		(fp_line
			(start -6.949948 5.7912)
			(end -6.949948 8.32993)
			(stroke
				(width 0.1524)
				(type default)
			)
			(layer "F.SilkS")
		)
		(fp_line
			(start -6.949948 0)
			(end -6.949948 4.5466)
			(stroke
				(width 0.1524)
				(type default)
			)
			(layer "F.SilkS")
		)
		(fp_line
			(start -6.949948 -3.670046)
			(end -6.949948 0)
			(stroke
				(width 0.1524)
				(type default)
			)
			(layer "F.SilkS")
		)
		(fp_poly
			(pts
				(xy -6.9596 0) (xy -8.7376 1.016) (xy -8.7376 -1.016)
			)
			(stroke
				(width 0)
				(type default)
			)
			(fill yes)
			(layer "F.SilkS")
		)
		(fp_poly
			(pts
				(arc
					(start 4.933188 5.180076)
					(mid 7.066788 5.180076)
					(end 4.933188 5.180076)
				)
			)
			(stroke
				(width 0)
				(type default)
			)
			(fill no)
			(layer "B.CrtYd")
		)
		(fp_poly
			(pts
				(arc
					(start -7.06755 5.180076)
					(mid -4.932426 5.180076)
					(end -7.06755 5.180076)
				)
			)
			(stroke
				(width 0)
				(type default)
			)
			(fill no)
			(layer "B.CrtYd")
		)
		(fp_poly
			(pts
				(xy -6.949948 8.32993) (xy 6.949948 8.32993) (xy 6.949948 -3.670046) (xy -6.949948 -3.670046)
			)
			(stroke
				(width 0)
				(type default)
			)
			(fill no)
			(layer "F.CrtYd")
		)
		(fp_line
			(start 6.949948 8.32993)
			(end 6.949948 -3.670046)
			(stroke
				(width 0.1)
				(type default)
			)
			(layer "F.Fab")
		)
		(fp_line
			(start 6.949948 -3.670046)
			(end -6.949948 -3.670046)
			(stroke
				(width 0.1)
				(type default)
			)
			(layer "F.Fab")
		)
		(fp_line
			(start -6.700012 0)
			(end -6.949948 0)
			(stroke
				(width 0.1)
				(type default)
			)
			(layer "F.Fab")
		)
		(fp_line
			(start -6.949948 8.32993)
			(end 6.949948 8.32993)
			(stroke
				(width 0.1)
				(type default)
			)
			(layer "F.Fab")
		)
		(fp_line
			(start -6.949948 0)
			(end -6.949948 8.32993)
			(stroke
				(width 0.1)
				(type default)
			)
			(layer "F.Fab")
		)
		(fp_line
			(start -6.949948 -3.670046)
			(end -6.949948 0)
			(stroke
				(width 0.1)
				(type default)
			)
			(layer "F.Fab")
		)
		(fp_poly
			(pts
				(xy -6.9596 0) (xy -8.7376 1.016) (xy -8.7376 -1.016)
			)
			(stroke
				(width 0)
				(type default)
			)
			(fill yes)
			(layer "F.Fab")
		)
		(fp_text user "A13"
			(at 12.41171 0.603504 90)
			(unlocked yes)
			(layer "F.SilkS")
			(effects
				(font
					(size 0.7874 0.5842)
					(thickness 0.1524)
				)
				(justify left)
			)
		)
		(fp_text user "B13"
			(at 12.254484 -6.279896 90)
			(unlocked yes)
			(layer "F.SilkS")
			(effects
				(font
					(size 0.7874 0.5842)
					(thickness 0.1524)
				)
				(justify left)
			)
		)
		(fp_text user "A1"
			(at -8.787892 -9.229852 0)
			(unlocked yes)
			(layer "F.SilkS")
			(effects
				(font
					(size 0.7874 0.5842)
					(thickness 0.1524)
				)
				(justify left)
			)
		)
		(fp_text user "B1"
			(at -8.838692 -10.225278 0)
			(unlocked yes)
			(layer "F.SilkS")
			(effects
				(font
					(size 0.7874 0.5842)
					(thickness 0.1524)
				)
				(justify left)
			)
		)
		(fp_text user "A13"
			(at 7.360666 -0.091948 180)
			(unlocked yes)
			(layer "F.Fab")
			(effects
				(font
					(size 0.7874 0.5842)
					(thickness 0.000001)
				)
				(justify left)
			)
		)
		(fp_text user "B13"
			(at 7.360666 -2.601722 180)
			(unlocked yes)
			(layer "F.Fab")
			(effects
				(font
					(size 0.7874 0.5842)
					(thickness 0.000001)
				)
				(justify left)
			)
		)
		(fp_text user "A1"
			(at -8.609584 1.330452 180)
			(unlocked yes)
			(layer "F.Fab")
			(effects
				(font
					(size 0.7874 0.5842)
					(thickness 0.000001)
				)
				(justify left)
			)
		)
		(fp_text user "B1"
			(at -8.685784 -2.601722 180)
			(unlocked yes)
			(layer "F.Fab")
			(effects
				(font
					(size 0.7874 0.5842)
					(thickness 0.000001)
				)
				(justify left)
			)
		)
		(pad "" np_thru_hole circle
			(at -5.999988 5.180076 180)
			(size 1.6002 1.6002)
			(drill 1.6002)
			(layers "*.Cu" "*.Mask")
			(clearance 0.381)
			(thermal_gap 0.381)
		)
		(pad "" np_thru_hole circle
			(at 5.999988 5.180076 180)
			(size 1.6002 1.6002)
			(drill 1.6002)
			(layers "*.Cu" "*.Mask")
			(clearance 0.381)
			(thermal_gap 0.381)
		)
		(pad "A1" smd rect
			(at -4.59994 0 180)
			(size 0.381 1.8542)
			(layers "F.Cu" "F.Mask" "F.Paste")
			(net "GND")
		)
		(pad "A2" smd rect
			(at -3.800094 0 180)
			(size 0.381 1.8542)
			(layers "F.Cu" "F.Mask" "F.Paste")
			(net "SAS_BLAD2_RX5_P")
		)
		(pad "A3" smd rect
			(at -2.999994 0 180)
			(size 0.381 1.8542)
			(layers "F.Cu" "F.Mask" "F.Paste")
			(net "SAS_BLAD2_RX5_N")
		)
		(pad "A4" smd rect
			(at -2.199894 0 180)
			(size 0.381 1.8542)
			(layers "F.Cu" "F.Mask" "F.Paste")
			(net "GND")
		)
		(pad "A5" smd rect
			(at -1.400048 0 180)
			(size 0.381 1.8542)
			(layers "F.Cu" "F.Mask" "F.Paste")
			(net "SAS_BLAD2_RX6_P")
		)
		(pad "A6" smd rect
			(at -0.599948 0 180)
			(size 0.381 1.8542)
			(layers "F.Cu" "F.Mask" "F.Paste")
			(net "SAS_BLAD2_RX6_N")
		)
		(pad "A7" smd rect
			(at 0.199898 0 180)
			(size 0.381 1.8542)
			(layers "F.Cu" "F.Mask" "F.Paste")
			(net "GND")
		)
		(pad "A8" smd rect
			(at 0.999998 0 180)
			(size 0.381 1.8542)
			(layers "F.Cu" "F.Mask" "F.Paste")
			(net "SAS_BLAD2_RX7_P")
		)
		(pad "A9" smd rect
			(at 1.800098 0 180)
			(size 0.381 1.8542)
			(layers "F.Cu" "F.Mask" "F.Paste")
			(net "SAS_BLAD2_RX7_N")
		)
		(pad "A10" smd rect
			(at 2.599944 0 180)
			(size 0.381 1.8542)
			(layers "F.Cu" "F.Mask" "F.Paste")
			(net "GND")
		)
		(pad "A11" smd rect
			(at 3.400044 0 180)
			(size 0.381 1.8542)
			(layers "F.Cu" "F.Mask" "F.Paste")
			(net "SAS_BLAD2_RX8_P")
		)
		(pad "A12" smd rect
			(at 4.19989 0 180)
			(size 0.381 1.8542)
			(layers "F.Cu" "F.Mask" "F.Paste")
			(net "SAS_BLAD2_RX8_N")
		)
		(pad "A13" smd rect
			(at 4.99999 0 180)
			(size 0.381 1.8542)
			(layers "F.Cu" "F.Mask" "F.Paste")
			(net "GND")
		)
		(pad "B1" smd rect
			(at -4.99999 -2.510028 180)
			(size 0.381 1.8542)
			(layers "F.Cu" "F.Mask" "F.Paste")
			(net "GND")
		)
		(pad "B2" smd rect
			(at -4.19989 -2.510028 180)
			(size 0.381 1.8542)
			(layers "F.Cu" "F.Mask" "F.Paste")
			(net "SAS_BLAD2_TX5_P")
		)
		(pad "B3" smd rect
			(at -3.400044 -2.510028 180)
			(size 0.381 1.8542)
			(layers "F.Cu" "F.Mask" "F.Paste")
			(net "SAS_BLAD2_TX5_N")
		)
		(pad "B4" smd rect
			(at -2.599944 -2.510028 180)
			(size 0.381 1.8542)
			(layers "F.Cu" "F.Mask" "F.Paste")
			(net "GND")
		)
		(pad "B5" smd rect
			(at -1.800098 -2.510028 180)
			(size 0.381 1.8542)
			(layers "F.Cu" "F.Mask" "F.Paste")
			(net "SAS_BLAD2_TX6_P")
		)
		(pad "B6" smd rect
			(at -0.999998 -2.510028 180)
			(size 0.381 1.8542)
			(layers "F.Cu" "F.Mask" "F.Paste")
			(net "SAS_BLAD2_TX6_N")
		)
		(pad "B7" smd rect
			(at -0.199898 -2.510028 180)
			(size 0.381 1.8542)
			(layers "F.Cu" "F.Mask" "F.Paste")
			(net "GND")
		)
		(pad "B8" smd rect
			(at 0.599948 -2.510028 180)
			(size 0.381 1.8542)
			(layers "F.Cu" "F.Mask" "F.Paste")
			(net "SAS_BLAD2_TX7_P")
		)
		(pad "B9" smd rect
			(at 1.400048 -2.510028 180)
			(size 0.381 1.8542)
			(layers "F.Cu" "F.Mask" "F.Paste")
			(net "SAS_BLAD2_TX7_N")
		)
		(pad "B10" smd rect
			(at 2.199894 -2.510028 180)
			(size 0.381 1.8542)
			(layers "F.Cu" "F.Mask" "F.Paste")
			(net "GND")
		)
		(pad "B11" smd rect
			(at 2.999994 -2.510028 180)
			(size 0.381 1.8542)
			(layers "F.Cu" "F.Mask" "F.Paste")
			(net "SAS_BLAD2_TX8_P")
		)
		(pad "B12" smd rect
			(at 3.800094 -2.510028 180)
			(size 0.381 1.8542)
			(layers "F.Cu" "F.Mask" "F.Paste")
			(net "SAS_BLAD2_TX8_N")
		)
		(pad "B13" smd rect
			(at 4.59994 -2.510028 180)
			(size 0.381 1.8542)
			(layers "F.Cu" "F.Mask" "F.Paste")
			(net "GND")
		)
		(zone
			(layer "F.Cu")
			(hatch none 0.5)
			(connect_pads
				(clearance 0)
			)
			(min_thickness 0.25)
			(keepout
				(tracks not_allowed)
				(vias allowed)
				(pads allowed)
				(copperpour not_allowed)
				(footprints allowed)
			)
			(placement
				(enabled no)
				(sheetname "")
			)
			(fill
				(thermal_gap 0.5)
				(thermal_bridge_width 0.5)
				(island_removal_mode 0)
			)
			(polygon
				(pts
					(xy 388.404862 -36.73983) (xy 386.564886 -36.73983) (xy 386.564886 -35.279838) (xy 388.404862 -35.279838)
				)
			)
		)
		(zone
			(layer "F.Cu")
			(hatch none 0.5)
			(connect_pads
				(clearance 0)
			)
			(min_thickness 0.25)
			(keepout
				(tracks not_allowed)
				(vias allowed)
				(pads allowed)
				(copperpour not_allowed)
				(footprints allowed)
			)
			(placement
				(enabled no)
				(sheetname "")
			)
			(fill
				(thermal_gap 0.5)
				(thermal_bridge_width 0.5)
				(island_removal_mode 0)
			)
			(polygon
				(pts
					(xy 400.404838 -36.73983) (xy 398.564862 -36.73983) (xy 398.564862 -35.279838) (xy 400.404838 -35.279838)
				)
			)
		)
		(zone
			(layers "F.Cu" "B.Cu" "In1.Cu" "In2.Cu" "In3.Cu" "In4.Cu" "In5.Cu" "In6.Cu")
			(hatch none 0.5)
			(connect_pads
				(clearance 0)
			)
			(min_thickness 0.25)
			(keepout
				(tracks not_allowed)
				(vias allowed)
				(pads allowed)
				(copperpour not_allowed)
				(footprints allowed)
			)
			(placement
				(enabled no)
				(sheetname "")
			)
			(fill
				(thermal_gap 0.5)
				(thermal_bridge_width 0.5)
				(island_removal_mode 0)
			)
			(polygon
				(pts
					(arc
						(start 388.70382 -33.589976)
						(mid 386.265928 -33.589976)
						(end 388.70382 -33.589976)
					)
				)
			)
		)
		(zone
			(layers "F.Cu" "B.Cu" "In1.Cu" "In2.Cu" "In3.Cu" "In4.Cu" "In5.Cu" "In6.Cu")
			(hatch none 0.5)
			(connect_pads
				(clearance 0)
			)
			(min_thickness 0.25)
			(keepout
				(tracks not_allowed)
				(vias allowed)
				(pads allowed)
				(copperpour not_allowed)
				(footprints allowed)
			)
			(placement
				(enabled no)
				(sheetname "")
			)
			(fill
				(thermal_gap 0.5)
				(thermal_bridge_width 0.5)
				(island_removal_mode 0)
			)
			(polygon
				(pts
					(arc
						(start 400.704558 -33.589976)
						(mid 398.265142 -33.589976)
						(end 400.704558 -33.589976)
					)
				)
			)
		)
	)
	(footprint ""
		(layer "F.Cu")
		(at 117.31244 -23.27021)
		(property "Reference" "R6"
			(at -61.341 5.115052 0)
			(unlocked yes)
			(layer "F.SilkS")
			(effects
				(font
					(size 0.7874 0.5842)
					(thickness 0.1524)
				)
				(justify left)
			)
		)
		(property "Value" ""
			(at 0 0 0)
			(layer "F.Fab")
			(effects
				(font
					(size 1.27 1.27)
				)
			)
		)
		(duplicate_pad_numbers_are_jumpers no)
		(fp_line
			(start -0.7874 -0.4064)
			(end 0.7874 -0.4064)
			(stroke
				(width 0.1524)
				(type default)
			)
			(layer "F.SilkS")
		)
		(fp_line
			(start -0.7874 0.4064)
			(end -0.7874 -0.4064)
			(stroke
				(width 0.1524)
				(type default)
			)
			(layer "F.SilkS")
		)
		(fp_line
			(start 0.7874 -0.4064)
			(end 0.7874 0.4064)
			(stroke
				(width 0.1524)
				(type default)
			)
			(layer "F.SilkS")
		)
		(fp_line
			(start 0.7874 0.4064)
			(end -0.7874 0.4064)
			(stroke
				(width 0.1524)
				(type default)
			)
			(layer "F.SilkS")
		)
		(fp_poly
			(pts
				(xy -0.508 0.2794) (xy -0.508 0.2286) (xy -0.635 0.2286) (xy -0.635 -0.254) (xy -0.5334 -0.254)
				(xy -0.5334 -0.2794) (xy 0.5334 -0.2794) (xy 0.5334 -0.254) (xy 0.635 -0.254) (xy 0.635 0.254) (xy 0.5334 0.254)
				(xy 0.5334 0.2794)
			)
			(stroke
				(width 0)
				(type default)
			)
			(fill no)
			(layer "F.CrtYd")
		)
		(pad "1" smd rect
			(at 0.40005 0)
			(size 0.4572 0.508)
			(layers "F.Cu" "F.Mask" "F.Paste")
			(net "P3V3_BLAD1")
		)
		(pad "2" smd rect
			(at -0.40005 0)
			(size 0.4572 0.508)
			(layers "F.Cu" "F.Mask" "F.Paste")
			(net "ENET10G_2_SDA")
		)
	)
	(footprint ""
		(layer "F.Cu")
		(at 338.127848 -22.946106)
		(property "Reference" "R24"
			(at -58.3438 -4.587748 0)
			(unlocked yes)
			(layer "F.SilkS")
			(effects
				(font
					(size 0.7874 0.5842)
					(thickness 0.1524)
				)
				(justify left)
			)
		)
		(property "Value" ""
			(at 0 0 0)
			(layer "F.Fab")
			(effects
				(font
					(size 1.27 1.27)
				)
			)
		)
		(duplicate_pad_numbers_are_jumpers no)
		(fp_line
			(start -0.7874 -0.4064)
			(end 0.7874 -0.4064)
			(stroke
				(width 0.1524)
				(type default)
			)
			(layer "F.SilkS")
		)
		(fp_line
			(start -0.7874 0.4064)
			(end -0.7874 -0.4064)
			(stroke
				(width 0.1524)
				(type default)
			)
			(layer "F.SilkS")
		)
		(fp_line
			(start 0.7874 -0.4064)
			(end 0.7874 0.4064)
			(stroke
				(width 0.1524)
				(type default)
			)
			(layer "F.SilkS")
		)
		(fp_line
			(start 0.7874 0.4064)
			(end -0.7874 0.4064)
			(stroke
				(width 0.1524)
				(type default)
			)
			(layer "F.SilkS")
		)
		(fp_poly
			(pts
				(xy -0.508 0.2794) (xy -0.508 0.2286) (xy -0.635 0.2286) (xy -0.635 -0.254) (xy -0.5334 -0.254)
				(xy -0.5334 -0.2794) (xy 0.5334 -0.2794) (xy 0.5334 -0.254) (xy 0.635 -0.254) (xy 0.635 0.254) (xy 0.5334 0.254)
				(xy 0.5334 0.2794)
			)
			(stroke
				(width 0)
				(type default)
			)
			(fill no)
			(layer "F.CrtYd")
		)
		(pad "1" smd rect
			(at 0.40005 0)
			(size 0.4572 0.508)
			(layers "F.Cu" "F.Mask" "F.Paste")
			(net "P3V3_BLAD2")
		)
		(pad "2" smd rect
			(at -0.40005 0)
			(size 0.4572 0.508)
			(layers "F.Cu" "F.Mask" "F.Paste")
			(net "ENET10G_4_SCL")
		)
	)
	(footprint ""
		(layer "F.Cu")
		(at 156.0576 -28.488132 180)
		(property "Reference" "R76"
			(at -33.9344 -18.674334 0)
			(unlocked yes)
			(layer "F.SilkS")
			(effects
				(font
					(size 0.7874 0.5842)
					(thickness 0.1524)
				)
				(justify left)
			)
		)
		(property "Value" ""
			(at 0 0 180)
			(layer "F.Fab")
			(effects
				(font
					(size 1.27 1.27)
				)
			)
		)
		(duplicate_pad_numbers_are_jumpers no)
		(fp_line
			(start 1.905 0.8636)
			(end -1.905 0.8636)
			(stroke
				(width 0.1524)
				(type default)
			)
			(layer "F.SilkS")
		)
		(fp_line
			(start 1.905 -0.8636)
			(end 1.905 0.8636)
			(stroke
				(width 0.1524)
				(type default)
			)
			(layer "F.SilkS")
		)
		(fp_line
			(start -1.905 0.8636)
			(end -1.905 -0.8636)
			(stroke
				(width 0.1524)
				(type default)
			)
			(layer "F.SilkS")
		)
		(fp_line
			(start -1.905 -0.8636)
			(end 1.905 -0.8636)
			(stroke
				(width 0.1524)
				(type default)
			)
			(layer "F.SilkS")
		)
		(fp_poly
			(pts
				(xy 1.524 0.6858) (xy 1.524 -0.6858) (xy 1.524 -0.7366) (xy -1.524 -0.7366) (xy -1.524 -0.6858)
				(xy -1.524 0.6858) (xy -1.524 0.7366) (xy 1.524 0.7366)
			)
			(stroke
				(width 0)
				(type default)
			)
			(fill no)
			(layer "F.CrtYd")
		)
		(pad "1" smd rect
			(at 0.94996 0 180)
			(size 1.1176 1.3716)
			(layers "F.Cu" "F.Mask" "F.Paste")
			(net "P3V3_BLAD1")
		)
		(pad "2" smd rect
			(at -0.94996 0 180)
			(size 1.1176 1.3716)
			(layers "F.Cu" "F.Mask" "F.Paste")
			(net "P3V3_10G_1_VCCT")
		)
	)
	(footprint ""
		(layer "F.Cu")
		(at 155.064714 -37.841428)
		(property "Reference" "FS3"
			(at 35.23488 24.299164 0)
			(unlocked yes)
			(layer "F.SilkS")
			(effects
				(font
					(size 0.7874 0.5842)
					(thickness 0.1524)
				)
				(justify left)
			)
		)
		(property "Value" ""
			(at 0 0 0)
			(layer "F.Fab")
			(effects
				(font
					(size 1.27 1.27)
				)
			)
		)
		(duplicate_pad_numbers_are_jumpers no)
		(fp_line
			(start -0.650494 -1.050036)
			(end 3.550412 -1.050036)
			(stroke
				(width 0.1524)
				(type default)
			)
			(layer "F.SilkS")
		)
		(fp_line
			(start -0.650494 1.050036)
			(end -0.650494 -1.050036)
			(stroke
				(width 0.1524)
				(type default)
			)
			(layer "F.SilkS")
		)
		(fp_line
			(start 3.550412 -1.050036)
			(end 3.550412 1.050036)
			(stroke
				(width 0.1524)
				(type default)
			)
			(layer "F.SilkS")
		)
		(fp_line
			(start 3.550412 1.050036)
			(end -0.650494 1.050036)
			(stroke
				(width 0.1524)
				(type default)
			)
			(layer "F.SilkS")
		)
		(fp_poly
			(pts
				(xy 3.228086 -0.9652) (xy 3.228086 -1.100074) (xy -0.327914 -1.100074) (xy -0.327914 -0.9652) (xy -0.556514 -0.9652)
				(xy -0.556514 0.9652) (xy -0.327914 0.9652) (xy -0.327914 1.100074) (xy 3.228086 1.100074) (xy 3.228086 0.9652)
				(xy 3.456686 0.9652) (xy 3.456686 -0.9652)
			)
			(stroke
				(width 0)
				(type default)
			)
			(fill no)
			(layer "F.CrtYd")
		)
		(fp_text user "1"
			(at -1.201674 0.016764 0)
			(unlocked yes)
			(layer "F.SilkS")
			(effects
				(font
					(size 0.7874 0.5842)
					(thickness 0.1524)
				)
				(justify left)
			)
		)
		(fp_text user "2"
			(at 4.157726 -0.389636 0)
			(unlocked yes)
			(layer "F.SilkS")
			(effects
				(font
					(size 0.7874 0.5842)
					(thickness 0.1524)
				)
				(justify left)
			)
		)
		(pad "1" smd rect
			(at 0 0)
			(size 1.016 1.8034)
			(layers "F.Cu" "F.Mask" "F.Paste")
			(net "P3V3_BLAD1")
		)
		(pad "2" smd rect
			(at 2.899918 0)
			(size 1.016 1.8034)
			(layers "F.Cu" "F.Mask" "F.Paste")
			(net "P3V3_10G_1_VCCR_L")
		)
	)
)
